# T6G (Grand Teton) — schematic netlist excerpt (pin names and nets, part order shuffled) for the footprints in the layout excerpt that follows; sources: Cadence DE-HDL packaged netlist, KiCad conversion of 04192023_DAF0TMB3IC0_F0TG_MB_C_brd_V02_OCP.brd

J1  SCONN288_DDR506112002KQ  IO  pkg DDR288S_1-1VXC  page 86
  VIN_BULK0  = P12V_MEM_CPU0
  RFU0  = NC
  VIN_MGMT  = P3V3_AUX
  HSCL  = I3C_SPD_DDRA_CPU0_SCL
  HSDA  = I3C_SPD_DDRA_CPU0_SDA
  VSS0  = GND
  DQ0_A  = M_A_CPU0_SA_DQ<0>
  VSS1  = GND
  DQ1_A  = M_A_CPU0_SA_DQ<1>
  VSS2  = GND
  DQS0_A_T  = M_A_CPU0_SA_DQS_DP<0>
  DQS0_A_C  = M_A_CPU0_SA_DQS_DN<0>
  VSS3  = GND
  DQ4_A  = M_A_CPU0_SA_DQ<4>
  VSS4  = GND
  DQ5_A  = M_A_CPU0_SA_DQ<5>
  VSS5  = GND
  DQ8_A  = M_A_CPU0_SA_DQ<8>
  VSS6  = GND
  DQ9_A  = M_A_CPU0_SA_DQ<9>
  VSS7  = GND
  DQS1_A_T  = M_A_CPU0_SA_DQS_DP<1>
  DQS1_A_C  = M_A_CPU0_SA_DQS_DN<1>
  VSS8  = GND
  DQ12_A  = M_A_CPU0_SA_DQ<12>
  VSS9  = GND
  DQ13_A  = M_A_CPU0_SA_DQ<13>
  VSS10  = GND
  DQ16_A  = M_A_CPU0_SA_DQ<16>
  VSS11  = GND
  DQ17_A  = M_A_CPU0_SA_DQ<17>
  VSS12  = GND
  DQS2_A_T  = M_A_CPU0_SA_DQS_DP<2>
  DQS2_A_C  = M_A_CPU0_SA_DQS_DN<2>
  VSS13  = GND
  DQ20_A  = M_A_CPU0_SA_DQ<20>
  VSS14  = GND
  DQ21_A  = M_A_CPU0_SA_DQ<21>
  VSS15  = GND
  DQ24_A  = M_A_CPU0_SA_DQ<24>
  VSS16  = GND
  DQ25_A  = M_A_CPU0_SA_DQ<25>
  VSS17  = GND
  DQS3_A_T  = M_A_CPU0_SA_DQS_DP<3>
  DQS3_A_C  = M_A_CPU0_SA_DQS_DN<3>
  VSS18  = GND
  DQ28_A  = M_A_CPU0_SA_DQ<28>
  VSS19  = GND
  DQ29_A  = M_A_CPU0_SA_DQ<29>
  VSS20  = GND
  CB0_A  = M_A_CPU0_SA_CB<0>
  VSS21  = GND
  CB1_A  = M_A_CPU0_SA_CB<1>
  VSS22  = GND
  DQS4_A_T  = M_A_CPU0_SA_DQS_DP<4>
  DQS4_A_C  = M_A_CPU0_SA_DQS_DN<4>
  VSS23  = GND
  CB4_A  = M_A_CPU0_SA_CB<4>
  VSS24  = GND
  CB5_A  = M_A_CPU0_SA_CB<5>
  VSS25  = GND
  ALERT_N  = M_A_CPU0_ALERT_N
  VSS26  = GND
  CS0_A_N  = M_A_CPU0_SA_CS_N<0>
  VSS27  = GND
  CA0_A  = M_A_CPU0_SA_CA<0>
  VSS28  = GND
  CA2_A  = M_A_CPU0_SA_CA<2>
  VSS29  = GND
  CA4_A  = M_A_CPU0_SA_CA<4>
  VSS30  = GND
  CA6_A  = M_A_CPU0_SA_CA<6>
  VSS31  = GND
  PAR_A  = M_A_CPU0_SA_PAR
  VSS32  = GND
  CA0_B  = M_A_CPU0_SB_CA<0>
  VSS33  = GND
  CA2_B  = M_A_CPU0_SB_CA<2>
  VSS34  = GND
  CA4_B  = M_A_CPU0_SB_CA<4>
  VSS35  = GND
  CA6_B  = M_A_CPU0_SB_CA<6>
  VSS36  = GND
  CS0_B_N  = M_A_CPU0_SB_CS_N<0>
  VSS37  = GND
  \lbd||rsp_a_n\  = M_A_CPU0_SA_RSP<0>
  \lbs||rsp_b_n\  = M_A_CPU0_SB_RSP<0>
  VSS38  = GND
  CB4_B  = M_A_CPU0_SB_CB<4>
  VSS39  = GND
  CB5_B  = M_A_CPU0_SB_CB<5>
  VSS40  = GND
  \dqs9_b_t||tdqs9_b_t||dbi4_b_n\  = M_A_CPU0_SB_DQS_DP<9>
  \dqs9_b_c||tdqs9_b_c\  = M_A_CPU0_SB_DQS_DN<9>
  VSS41  = GND
  CB0_B  = M_A_CPU0_SB_CB<0>
  VSS42  = GND
  CB1_B  = M_A_CPU0_SB_CB<1>
  VSS43  = GND
  DQ0_B  = M_A_CPU0_SB_DQ<0>
  VSS44  = GND
  DQ1_B  = M_A_CPU0_SB_DQ<1>
  VSS45  = GND
  DQS0_B_T  = M_A_CPU0_SB_DQS_DP<0>
  DQS0_B_C  = M_A_CPU0_SB_DQS_DN<0>
  VSS46  = GND
  DQ4_B  = M_A_CPU0_SB_DQ<4>
  VSS47  = GND
  DQ5_B  = M_A_CPU0_SB_DQ<5>
  VSS48  = GND
  DQ8_B  = M_A_CPU0_SB_DQ<8>
  VSS49  = GND
  DQ9_B  = M_A_CPU0_SB_DQ<9>
  VSS50  = GND
  DQS1_B_T  = M_A_CPU0_SB_DQS_DP<1>
  DQS1_B_C  = M_A_CPU0_SB_DQS_DN<1>
  VSS51  = GND
  DQ12_B  = M_A_CPU0_SB_DQ<12>
  VSS52  = GND
  DQ13_B  = M_A_CPU0_SB_DQ<13>
  VSS53  = GND
  DQ16_B  = M_A_CPU0_SB_DQ<16>
  VSS54  = GND
  DQ17_B  = M_A_CPU0_SB_DQ<17>
  VSS55  = GND
  DQS2_B_T  = M_A_CPU0_SB_DQS_DP<2>
  DQS2_B_C  = M_A_CPU0_SB_DQS_DN<2>
  VSS56  = GND
  DQ20_B  = M_A_CPU0_SB_DQ<20>
  VSS57  = GND
  DQ21_B  = M_A_CPU0_SB_DQ<21>
  VSS58  = GND
  DQ24_B  = M_A_CPU0_SB_DQ<24>
  VSS59  = GND
  DQ25_B  = M_A_CPU0_SB_DQ<25>
  VSS60  = GND
  DQS3_B_T  = M_A_CPU0_SB_DQS_DP<3>
  DQS3_B_C  = M_A_CPU0_SB_DQS_DN<3>
  VSS61  = GND
  DQ28_B  = M_A_CPU0_SB_DQ<28>
  VSS62  = GND
  DQ29_B  = M_A_CPU0_SB_DQ<29>
  VSS63  = GND
  RFU1  = NC
  VIN_BULK1  = P12V_MEM_CPU0
  VIN_BULK2  = P12V_MEM_CPU0
  \pwr_good||fail_n\  = PWRGD_CHA_CPU0_DIMM0
  HAS  = PD_CHA_CPU0_DIMM0_SAA
  RFU2  = NC
  RFU3  = NC
  VSS64  = GND
  DQ2_A  = M_A_CPU0_SA_DQ<2>
  VSS65  = GND
  DQ3_A  = M_A_CPU0_SA_DQ<3>
  VSS66  = GND
  \dqs5_a_c||tdqs5_a_c||dqs5_a_t||tdqs5_a_t\  = M_A_CPU0_SA_DQS_DN<5>
  \dqs5_a_t||tdqs5_a_t\  = M_A_CPU0_SA_DQS_DP<5>
  VSS67  = GND
  DQ6_A  = M_A_CPU0_SA_DQ<6>
  VSS68  = GND
  DQ7_A  = M_A_CPU0_SA_DQ<7>
  VSS69  = GND
  DQ10_A  = M_A_CPU0_SA_DQ<10>
  VSS70  = GND
  DQ11_A  = M_A_CPU0_SA_DQ<11>
  VSS71  = GND
  \dqs6_a_c||tdqs6_a_c||dqs6_a_t||tdqs6_a_t\  = M_A_CPU0_SA_DQS_DN<6>
  \dqs6_a_t||tdqs6_a_t\  = M_A_CPU0_SA_DQS_DP<6>
  VSS72  = GND
  DQ14_A  = M_A_CPU0_SA_DQ<14>
  VSS73  = GND
  DQ15_A  = M_A_CPU0_SA_DQ<15>
  VSS74  = GND
  DQ18_A  = M_A_CPU0_SA_DQ<18>
  VSS75  = GND
  DQ19_A  = M_A_CPU0_SA_DQ<19>
  VSS76  = GND
  \dqs7_a_c||tdqs7_a_c\  = M_A_CPU0_SA_DQS_DN<7>
  \dqs7_a_t||tdqs7_a_t\  = M_A_CPU0_SA_DQS_DP<7>
  VSS77  = GND
  DQ22_A  = M_A_CPU0_SA_DQ<22>
  VSS78  = GND
  DQ23_A  = M_A_CPU0_SA_DQ<23>
  VSS79  = GND
  DQ26_A  = M_A_CPU0_SA_DQ<26>
  VSS80  = GND
  DQ27_A  = M_A_CPU0_SA_DQ<27>
  VSS81  = GND
  \dqs8_a_c||tdqs8_a_c\  = M_A_CPU0_SA_DQS_DN<8>
  \dqs8_a_t||tdqs8_a_t\  = M_A_CPU0_SA_DQS_DP<8>
  VSS82  = GND
  DQ30_A  = M_A_CPU0_SA_DQ<30>
  VSS83  = GND
  DQ31_A  = M_A_CPU0_SA_DQ<31>
  VSS84  = GND
  CB2_A  = M_A_CPU0_SA_CB<2>
  VSS85  = GND
  CB3_A  = M_A_CPU0_SA_CB<3>
  VSS86  = GND
  \dqs9_a_c||tdqs9_a_c\  = M_A_CPU0_SA_DQS_DN<9>
  \dqs9_a_t||tdqs9_a_t\  = M_A_CPU0_SA_DQS_DP<9>
  VSS87  = GND
  CB6_A  = M_A_CPU0_SA_CB<6>
  VSS88  = GND
  CB7_A  = M_A_CPU0_SA_CB<7>
  VSS89  = GND
  RESET_N  = M_A_CPU0_RESET_N
  VSS90  = GND
  CS1_A_N  = M_A_CPU0_SA_CS_N<1>
  VSS91  = GND
  CA1_A  = M_A_CPU0_SA_CA<1>
  VSS92  = GND
  CA3_A  = M_A_CPU0_SA_CA<3>
  VSS93  = GND
  CA5_A  = M_A_CPU0_SA_CA<5>
  VSS94  = GND
  CK_T  = M_A_CPU0_CLK_DP<0>
  CK_C  = M_A_CPU0_CLK_DN<0>
  VSS95  = GND
  RFU4  = NC
  CA1_B  = M_A_CPU0_SB_CA<1>
  VSS96  = GND
  CA3_B  = M_A_CPU0_SB_CA<3>
  VSS97  = GND
  CA5_B  = M_A_CPU0_SB_CA<5>
  VSS98  = GND
  PAR_B  = M_A_CPU0_SB_PAR
  VSS99  = GND
  CS1_B_N  = M_A_CPU0_SB_CS_N<1>
  VSS100  = GND
  RFU5  = NC
  RFU6  = NC
  VSS101  = GND
  CB6_B  = M_A_CPU0_SB_CB<6>
  VSS102  = GND
  CB7_B  = M_A_CPU0_SB_CB<7>
  VSS103  = GND
  DQS4_B_C  = M_A_CPU0_SB_DQS_DN<4>
  DQS4_B_T  = M_A_CPU0_SB_DQS_DP<4>
  VSS104  = GND
  CB2_B  = M_A_CPU0_SB_CB<2>
  VSS105  = GND
  CB3_B  = M_A_CPU0_SB_CB<3>
  VSS106  = GND
  DQ2_B  = M_A_CPU0_SB_DQ<2>
  VSS107  = GND
  DQ3_B  = M_A_CPU0_SB_DQ<3>
  VSS108  = GND
  \dqs5_b_c||tdqs5_b_c\  = M_A_CPU0_SB_DQS_DN<5>
  \dqs5_b_t||tdqs5_b_t\  = M_A_CPU0_SB_DQS_DP<5>
  VSS109  = GND
  DQ6_B  = M_A_CPU0_SB_DQ<6>
  VSS110  = GND
  DQ7_B  = M_A_CPU0_SB_DQ<7>
  VSS111  = GND
  DQ10_B  = M_A_CPU0_SB_DQ<10>
  VSS112  = GND
  DQ11_B  = M_A_CPU0_SB_DQ<11>
  VSS113  = GND
  \dqs6_b_c||tdqs6_b_c\  = M_A_CPU0_SB_DQS_DN<6>
  \dqs6_b_t||tdqs6_b_t\  = M_A_CPU0_SB_DQS_DP<6>
  VSS114  = GND
  DQ14_B  = M_A_CPU0_SB_DQ<14>
  VSS115  = GND
  DQ15_B  = M_A_CPU0_SB_DQ<15>
  VSS116  = GND
  DQ18_B  = M_A_CPU0_SB_DQ<18>
  VSS117  = GND
  DQ19_B  = M_A_CPU0_SB_DQ<19>
  VSS118  = GND
  \dqs7_b_c||tdqs7_b_c\  = M_A_CPU0_SB_DQS_DN<7>
  \dqs7_b_t||tdqs7_b_t\  = M_A_CPU0_SB_DQS_DP<7>
  VSS119  = GND
  DQ22_B  = M_A_CPU0_SB_DQ<22>
  VSS120  = GND
  DQ23_B  = M_A_CPU0_SB_DQ<23>
  VSS121  = GND
  DQ26_B  = M_A_CPU0_SB_DQ<26>
  VSS122  = GND
  DQ27_B  = M_A_CPU0_SB_DQ<27>
  VSS123  = GND
  \dqs8_b_c||tdqs8_b_c\  = M_A_CPU0_SB_DQS_DN<8>
  \dqs8_b_t||tdqs8_b_t\  = M_A_CPU0_SB_DQS_DP<8>
  VSS124  = GND
  DQ30_B  = M_A_CPU0_SB_DQ<30>
  VSS125  = GND
  DQ31_B  = M_A_CPU0_SB_DQ<31>
  VSS126  = GND
  G1  = GND
  G2  = GND
  G3  = GND

(kicad_pcb
	(version 20260206)
	(generator "pcbnew")
	(generator_version "10.0")
	(general
		(thickness 1.6)
		(legacy_teardrops no)
	)
	(paper "A4")
	(title_block
		(title "04192023_DAF0TMB3IC0_F0TG_MB_C_brd_V02_OCP.brd")
		(comment 1 "Grand Teton / footprint 2352 of 8354 (J1), pads 47-92 of 291")
	)
	(layers
		(0 "F.Cu" signal "TOP")
		(4 "In1.Cu" signal "GND")
		(6 "In2.Cu" signal "IN1")
		(8 "In3.Cu" signal "GND1")
		(10 "In4.Cu" signal "IN2")
		(12 "In5.Cu" signal "GND2")
		(14 "In6.Cu" signal "IN3")
		(16 "In7.Cu" signal "GND3")
		(18 "In8.Cu" signal "VCC")
		(20 "In9.Cu" signal "VCC1")
		(22 "In10.Cu" signal "GND4")
		(24 "In11.Cu" signal "IN4")
		(26 "In12.Cu" signal "GND5")
		(28 "In13.Cu" signal "IN5")
		(30 "In14.Cu" signal "GND6")
		(32 "In15.Cu" signal "IN6")
		(34 "In16.Cu" signal "GND7")
		(2 "B.Cu" signal "BOTTOM")
		(9 "F.Adhes" user "F.Adhesive")
		(11 "B.Adhes" user "B.Adhesive")
		(13 "F.Paste" user "Package Geometry/Pastemask Top")
		(15 "B.Paste" user "Package Geometry/Pastemask Bottom")
		(5 "F.SilkS" user "Ref Des/Silkscreen Top")
		(7 "B.SilkS" user "Ref Des/Silkscreen Bottom")
		(1 "F.Mask" user "Board Geometry/Soldermask Top")
		(3 "B.Mask" user "Board Geometry/Soldermask Bottom")
		(17 "Dwgs.User" user "User.Drawings")
		(19 "Cmts.User" user "User.Comments")
		(21 "Eco1.User" user "User.Eco1")
		(23 "Eco2.User" user "User.Eco2")
		(25 "Edge.Cuts" user "Board Geometry/Outline")
		(27 "Margin" user)
		(31 "F.CrtYd" user "Package Geometry/Place Bound Top")
		(29 "B.CrtYd" user "Package Geometry/Place Bound Bottom")
		(35 "F.Fab" user "Ref Des/Assembly Top")
		(33 "B.Fab" user "Ref Des/Assembly Bottom")
	)
	(footprint ""
		(layer "F.Cu")
		(at 305.31816 -255.560068 180)
		(property "Reference" "J1"
			(at -2.2098 -81.984088 0)
			(unlocked yes)
			(layer "F.SilkS")
			(effects
				(font
					(size 0.7874 0.5842)
					(thickness 0.1524)
				)
			)
		)
		(property "Value" ""
			(at 0 0 180)
			(layer "F.Fab")
			(effects
				(font
					(size 1.27 1.27)
				)
			)
		)
		(duplicate_pad_numbers_are_jumpers no)
		(pad "47" smd rect
			(at -2.050034 -24.224996 90)
			(size 0.519938 1.4986)
			(layers "F.Cu" "F.Mask" "F.Paste")
			(net "M_A_CPU0_SA_DQ<28>")
		)
		(pad "48" smd rect
			(at -2.050034 -23.375112 90)
			(size 0.519938 1.4986)
			(layers "F.Cu" "F.Mask" "F.Paste")
			(net "GND")
		)
		(pad "49" smd rect
			(at -2.050034 -22.524974 90)
			(size 0.519938 1.4986)
			(layers "F.Cu" "F.Mask" "F.Paste")
			(net "M_A_CPU0_SA_DQ<29>")
		)
		(pad "50" smd rect
			(at -2.050034 -21.67509 90)
			(size 0.519938 1.4986)
			(layers "F.Cu" "F.Mask" "F.Paste")
			(net "GND")
		)
		(pad "51" smd rect
			(at -2.050034 -20.824952 90)
			(size 0.519938 1.4986)
			(layers "F.Cu" "F.Mask" "F.Paste")
			(net "M_A_CPU0_SA_CB<0>")
		)
		(pad "52" smd rect
			(at -2.050034 -19.975068 90)
			(size 0.519938 1.4986)
			(layers "F.Cu" "F.Mask" "F.Paste")
			(net "GND")
		)
		(pad "53" smd rect
			(at -2.050034 -19.12493 90)
			(size 0.519938 1.4986)
			(layers "F.Cu" "F.Mask" "F.Paste")
			(net "M_A_CPU0_SA_CB<1>")
		)
		(pad "54" smd rect
			(at -2.050034 -18.275046 90)
			(size 0.519938 1.4986)
			(layers "F.Cu" "F.Mask" "F.Paste")
			(net "GND")
		)
		(pad "55" smd rect
			(at -2.050034 -17.424908 90)
			(size 0.519938 1.4986)
			(layers "F.Cu" "F.Mask" "F.Paste")
			(net "M_A_CPU0_SA_DQS_DP<4>")
		)
		(pad "56" smd rect
			(at -2.050034 -16.575024 90)
			(size 0.519938 1.4986)
			(layers "F.Cu" "F.Mask" "F.Paste")
			(net "M_A_CPU0_SA_DQS_DN<4>")
		)
		(pad "57" smd rect
			(at -2.050034 -15.724886 90)
			(size 0.519938 1.4986)
			(layers "F.Cu" "F.Mask" "F.Paste")
			(net "GND")
		)
		(pad "58" smd rect
			(at -2.050034 -14.875002 90)
			(size 0.519938 1.4986)
			(layers "F.Cu" "F.Mask" "F.Paste")
			(net "M_A_CPU0_SA_CB<4>")
		)
		(pad "59" smd rect
			(at -2.050034 -14.025118 90)
			(size 0.519938 1.4986)
			(layers "F.Cu" "F.Mask" "F.Paste")
			(net "GND")
		)
		(pad "60" smd rect
			(at -2.050034 -13.17498 90)
			(size 0.519938 1.4986)
			(layers "F.Cu" "F.Mask" "F.Paste")
			(net "M_A_CPU0_SA_CB<5>")
		)
		(pad "61" smd rect
			(at -2.050034 -12.325096 90)
			(size 0.519938 1.4986)
			(layers "F.Cu" "F.Mask" "F.Paste")
			(net "GND")
		)
		(pad "62" smd rect
			(at -2.050034 -11.474958 90)
			(size 0.519938 1.4986)
			(layers "F.Cu" "F.Mask" "F.Paste")
			(net "M_A_CPU0_ALERT_N")
		)
		(pad "63" smd rect
			(at -2.050034 -10.625074 90)
			(size 0.519938 1.4986)
			(layers "F.Cu" "F.Mask" "F.Paste")
			(net "GND")
		)
		(pad "64" smd rect
			(at -2.050034 -9.774936 90)
			(size 0.519938 1.4986)
			(layers "F.Cu" "F.Mask" "F.Paste")
			(net "M_A_CPU0_SA_CS_N<0>")
		)
		(pad "65" smd rect
			(at -2.050034 -8.925052 90)
			(size 0.519938 1.4986)
			(layers "F.Cu" "F.Mask" "F.Paste")
			(net "GND")
		)
		(pad "66" smd rect
			(at -2.050034 -8.074914 90)
			(size 0.519938 1.4986)
			(layers "F.Cu" "F.Mask" "F.Paste")
			(net "M_A_CPU0_SA_CA<0>")
		)
		(pad "67" smd rect
			(at -2.050034 -7.22503 90)
			(size 0.519938 1.4986)
			(layers "F.Cu" "F.Mask" "F.Paste")
			(net "GND")
		)
		(pad "68" smd rect
			(at -2.050034 -6.374892 90)
			(size 0.519938 1.4986)
			(layers "F.Cu" "F.Mask" "F.Paste")
			(net "M_A_CPU0_SA_CA<2>")
		)
		(pad "69" smd rect
			(at -2.050034 -5.525008 90)
			(size 0.519938 1.4986)
			(layers "F.Cu" "F.Mask" "F.Paste")
			(net "GND")
		)
		(pad "70" smd rect
			(at -2.050034 -4.675124 90)
			(size 0.519938 1.4986)
			(layers "F.Cu" "F.Mask" "F.Paste")
			(net "M_A_CPU0_SA_CA<4>")
		)
		(pad "71" smd rect
			(at -2.050034 -3.824986 90)
			(size 0.519938 1.4986)
			(layers "F.Cu" "F.Mask" "F.Paste")
			(net "GND")
		)
		(pad "72" smd rect
			(at -2.050034 -2.975102 90)
			(size 0.519938 1.4986)
			(layers "F.Cu" "F.Mask" "F.Paste")
			(net "M_A_CPU0_SA_CA<6>")
		)
		(pad "73" smd rect
			(at -2.050034 -2.124964 90)
			(size 0.519938 1.4986)
			(layers "F.Cu" "F.Mask" "F.Paste")
			(net "GND")
		)
		(pad "74" smd rect
			(at -2.050034 -1.27508 90)
			(size 0.519938 1.4986)
			(layers "F.Cu" "F.Mask" "F.Paste")
			(net "M_A_CPU0_SA_PAR")
		)
		(pad "75" smd rect
			(at -2.050034 -0.424942 90)
			(size 0.519938 1.4986)
			(layers "F.Cu" "F.Mask" "F.Paste")
			(net "GND")
		)
		(pad "76" smd rect
			(at -2.050034 5.525008 90)
			(size 0.519938 1.4986)
			(layers "F.Cu" "F.Mask" "F.Paste")
			(net "M_A_CPU0_SB_CA<0>")
		)
		(pad "77" smd rect
			(at -2.050034 6.374892 90)
			(size 0.519938 1.4986)
			(layers "F.Cu" "F.Mask" "F.Paste")
			(net "GND")
		)
		(pad "78" smd rect
			(at -2.050034 7.22503 90)
			(size 0.519938 1.4986)
			(layers "F.Cu" "F.Mask" "F.Paste")
			(net "M_A_CPU0_SB_CA<2>")
		)
		(pad "79" smd rect
			(at -2.050034 8.074914 90)
			(size 0.519938 1.4986)
			(layers "F.Cu" "F.Mask" "F.Paste")
			(net "GND")
		)
		(pad "80" smd rect
			(at -2.050034 8.925052 90)
			(size 0.519938 1.4986)
			(layers "F.Cu" "F.Mask" "F.Paste")
			(net "M_A_CPU0_SB_CA<4>")
		)
		(pad "81" smd rect
			(at -2.050034 9.774936 90)
			(size 0.519938 1.4986)
			(layers "F.Cu" "F.Mask" "F.Paste")
			(net "GND")
		)
		(pad "82" smd rect
			(at -2.050034 10.625074 90)
			(size 0.519938 1.4986)
			(layers "F.Cu" "F.Mask" "F.Paste")
			(net "M_A_CPU0_SB_CA<6>")
		)
		(pad "83" smd rect
			(at -2.050034 11.474958 90)
			(size 0.519938 1.4986)
			(layers "F.Cu" "F.Mask" "F.Paste")
			(net "GND")
		)
		(pad "84" smd rect
			(at -2.050034 12.325096 90)
			(size 0.519938 1.4986)
			(layers "F.Cu" "F.Mask" "F.Paste")
			(net "M_A_CPU0_SB_CS_N<0>")
		)
		(pad "85" smd rect
			(at -2.050034 13.17498 90)
			(size 0.519938 1.4986)
			(layers "F.Cu" "F.Mask" "F.Paste")
			(net "GND")
		)
		(pad "86" smd rect
			(at -2.050034 14.025118 90)
			(size 0.519938 1.4986)
			(layers "F.Cu" "F.Mask" "F.Paste")
			(net "M_A_CPU0_SA_RSP<0>")
		)
		(pad "87" smd rect
			(at -2.050034 14.875002 90)
			(size 0.519938 1.4986)
			(layers "F.Cu" "F.Mask" "F.Paste")
			(net "M_A_CPU0_SB_RSP<0>")
		)
		(pad "88" smd rect
			(at -2.050034 15.724886 90)
			(size 0.519938 1.4986)
			(layers "F.Cu" "F.Mask" "F.Paste")
			(net "GND")
		)
		(pad "89" smd rect
			(at -2.050034 16.575024 90)
			(size 0.519938 1.4986)
			(layers "F.Cu" "F.Mask" "F.Paste")
			(net "M_A_CPU0_SB_CB<4>")
		)
		(pad "90" smd rect
			(at -2.050034 17.424908 90)
			(size 0.519938 1.4986)
			(layers "F.Cu" "F.Mask" "F.Paste")
			(net "GND")
		)
		(pad "91" smd rect
			(at -2.050034 18.275046 90)
			(size 0.519938 1.4986)
			(layers "F.Cu" "F.Mask" "F.Paste")
			(net "M_A_CPU0_SB_CB<5>")
		)
		(pad "92" smd rect
			(at -2.050034 19.12493 90)
			(size 0.519938 1.4986)
			(layers "F.Cu" "F.Mask" "F.Paste")
			(net "GND")
		)
	)
)
